FILE_TYPE = MACRO_DRAWING;
SET COLOR_WIRE YELLOW;
SET COLOR_PROP ORANGE;
SET COLOR_DOT WHITE;
SET COLOR_ARC YELLOW;
SET COLOR_BODY GREEN;
SET COLOR_NOTE PURPLE;
SET PROP_DISPLAY VALUE;
SET PAGE_NUMBER P137;
FORCEADD UNIVERSAL_GND..1
(-8175 -2025);
FORCEPROP 3 LASTPIN (-8175 -1975) SIG_NAME GND\g
J 0
(-8165 -1965);
DISPLAY 0.659574 (-8165 -1965);
PAINT MONO (-8165 -1965);
DISPLAY INVISIBLE (-8165 -1965);
FORCEPROP 1 LAST PATH I101
J 0
(-8100 -2025);
DISPLAY 0.872340 (-8100 -2025);
PAINT AQUA (-8100 -2025);
DISPLAY INVISIBLE (-8100 -2025);
FORCEPROP 2 LAST CDS_LIB logical_power
J 0
(-8175 -2025);
PAINT MONO (-8175 -2025);
DISPLAY INVISIBLE (-8175 -2025);
FORCEPROP 1 LAST HDL_POWER GND
J 1
(-8150 -2100);
DISPLAY 0.872340 (-8150 -2100);
PAINT GREEN (-8150 -2100);
DISPLAY INVISIBLE (-8150 -2100);
FORCEADD Q_RES..2
R 2
(-8175 -1775);
FORCEPROP 1 LAST PART_NUMBER CS21002FB06
J 2
(-8215 -1950);
DISPLAY 0.510638 (-8215 -1950);
DISPLAY INVISIBLE (-8215 -1950);
FORCEPROP 1 LAST TOLERANCE 1%
J 2
(-8220 -1750);
DISPLAY 0.510638 (-8220 -1750);
FORCEPROP 1 LAST PACK_TYPE 0402LF
J 2
(-8215 -1900);
DISPLAY 0.510638 (-8215 -1900);
FORCEPROP 1 LAST MATERIAL EMPTY
J 2
(-8215 -1850);
DISPLAY 0.510638 (-8215 -1850);
PAINT RED (-8215 -1850);
FORCEPROP 1 LAST WATTAGE 1/16W
J 2
(-8215 -1800);
DISPLAY 0.510638 (-8215 -1800);
FORCEPROP 1 LAST VALUE 1K
J 2
(-8220 -1700);
DISPLAY 0.510638 (-8220 -1700);
FORCEPROP 1 LAST $LOCATION R3025
J 2
(-8220 -1650);
DISPLAY 0.978723 (-8220 -1650);
FORCEPROP 1 LASTPIN (-8175 -1675) $PN 1
J 2
(-8180 -1713);
DISPLAY 0.787234 (-8180 -1713);
FORCEPROP 1 LASTPIN (-8175 -1875) $PN 2
J 2
(-8180 -1865);
DISPLAY 0.787234 (-8180 -1865);
FORCEPROP 2 LAST CDS_LIB pure_quanta
J 2
(-8175 -1775);
PAINT MONO (-8175 -1775);
DISPLAY INVISIBLE (-8175 -1775);
FORCEPROP 1 LAST PATH I102
J 2
(-8225 -1600);
DISPLAY 0.978723 (-8225 -1600);
PAINT WHITE (-8225 -1600);
DISPLAY INVISIBLE (-8225 -1600);
FORCEPROP 2 LAST CDS_LOCATION R3025
J 0
(-8225 -1550);
DISPLAY 1.021277 (-8225 -1550);
DISPLAY INVISIBLE (-8225 -1550);
FORCEPROP 2 LAST $SEC 1
J 0
(-8225 -1550);
DISPLAY 0.680851 (-8225 -1550);
PAINT MONO (-8225 -1550);
DISPLAY INVISIBLE (-8225 -1550);
FORCEPROP 2 LAST CDS_SEC 1
J 0
(-8225 -1550);
DISPLAY 1.021277 (-8225 -1550);
DISPLAY INVISIBLE (-8225 -1550);
FORCEADD Q_RES..2
(-7400 -2950);
FORCEPROP 1 LAST PART_NUMBER CS21002FB06
J 0
(-7360 -3125);
DISPLAY 0.510638 (-7360 -3125);
DISPLAY INVISIBLE (-7360 -3125);
FORCEPROP 1 LAST TOLERANCE 1%
J 0
(-7355 -2925);
DISPLAY 0.510638 (-7355 -2925);
FORCEPROP 1 LAST WATTAGE 1/16W
J 0
(-7360 -2975);
DISPLAY 0.510638 (-7360 -2975);
FORCEPROP 1 LAST PACK_TYPE 0402LF
J 0
(-7360 -3075);
DISPLAY 0.510638 (-7360 -3075);
FORCEPROP 1 LAST MATERIAL CHIP
J 0
(-7360 -3025);
DISPLAY 0.510638 (-7360 -3025);
FORCEPROP 1 LAST VALUE 1K
J 0
(-7355 -2875);
DISPLAY 0.510638 (-7355 -2875);
FORCEPROP 1 LAST $LOCATION R1374
J 0
(-7355 -2825);
DISPLAY 0.978723 (-7355 -2825);
FORCEPROP 1 LASTPIN (-7400 -2850) $PN 1
J 0
(-7395 -2888);
DISPLAY 0.787234 (-7395 -2888);
FORCEPROP 1 LASTPIN (-7400 -3050) $PN 2
J 0
(-7395 -3040);
DISPLAY 0.787234 (-7395 -3040);
FORCEPROP 2 LAST CDS_LIB pure_quanta
J 0
(-7400 -2950);
PAINT MONO (-7400 -2950);
DISPLAY INVISIBLE (-7400 -2950);
FORCEPROP 1 LAST PATH I103
J 0
(-7350 -2775);
DISPLAY 0.978723 (-7350 -2775);
PAINT WHITE (-7350 -2775);
DISPLAY INVISIBLE (-7350 -2775);
FORCEPROP 2 LAST CDS_LOCATION R1374
J 0
(-7350 -2725);
DISPLAY 1.021277 (-7350 -2725);
DISPLAY INVISIBLE (-7350 -2725);
FORCEPROP 2 LAST $SEC 1
J 0
(-7350 -2725);
DISPLAY 0.680851 (-7350 -2725);
PAINT MONO (-7350 -2725);
DISPLAY INVISIBLE (-7350 -2725);
FORCEPROP 2 LAST CDS_SEC 1
J 0
(-7350 -2725);
DISPLAY 1.021277 (-7350 -2725);
DISPLAY INVISIBLE (-7350 -2725);
FORCEADD UNIVERSAL_GND..1
(-7400 -3225);
FORCEPROP 3 LASTPIN (-7400 -3175) SIG_NAME GND\g
J 0
(-7390 -3165);
DISPLAY 0.659574 (-7390 -3165);
PAINT MONO (-7390 -3165);
DISPLAY INVISIBLE (-7390 -3165);
FORCEPROP 1 LAST HDL_POWER GND
J 1
(-7375 -3300);
DISPLAY 0.872340 (-7375 -3300);
PAINT GREEN (-7375 -3300);
DISPLAY INVISIBLE (-7375 -3300);
FORCEPROP 2 LAST CDS_LIB logical_power
J 0
(-7400 -3225);
PAINT MONO (-7400 -3225);
DISPLAY INVISIBLE (-7400 -3225);
FORCEPROP 1 LAST PATH I104
J 0
(-7325 -3225);
DISPLAY 0.872340 (-7325 -3225);
PAINT AQUA (-7325 -3225);
DISPLAY INVISIBLE (-7325 -3225);
FORCEADD Q_RES..2
(-7625 -2950);
FORCEPROP 1 LAST PART_NUMBER CS21002FB06
J 0
(-7585 -3125);
DISPLAY 0.510638 (-7585 -3125);
DISPLAY INVISIBLE (-7585 -3125);
FORCEPROP 1 LAST MATERIAL CHIP
J 0
(-7585 -3025);
DISPLAY 0.510638 (-7585 -3025);
FORCEPROP 1 LAST WATTAGE 1/16W
J 0
(-7585 -2975);
DISPLAY 0.510638 (-7585 -2975);
FORCEPROP 1 LAST VALUE 1K
J 0
(-7580 -2875);
DISPLAY 0.510638 (-7580 -2875);
FORCEPROP 1 LAST TOLERANCE 1%
J 0
(-7580 -2925);
DISPLAY 0.510638 (-7580 -2925);
FORCEPROP 1 LAST PACK_TYPE 0402LF
J 0
(-7585 -3075);
DISPLAY 0.510638 (-7585 -3075);
FORCEPROP 1 LAST $LOCATION R3027
J 0
(-7580 -2825);
DISPLAY 0.978723 (-7580 -2825);
FORCEPROP 1 LASTPIN (-7625 -2850) $PN 1
J 0
(-7620 -2888);
DISPLAY 0.787234 (-7620 -2888);
FORCEPROP 1 LASTPIN (-7625 -3050) $PN 2
J 0
(-7620 -3040);
DISPLAY 0.787234 (-7620 -3040);
FORCEPROP 2 LAST CDS_LIB pure_quanta
J 0
(-7625 -2950);
PAINT MONO (-7625 -2950);
DISPLAY INVISIBLE (-7625 -2950);
FORCEPROP 1 LAST PATH I105
J 0
(-7575 -2775);
DISPLAY 0.978723 (-7575 -2775);
PAINT WHITE (-7575 -2775);
DISPLAY INVISIBLE (-7575 -2775);
FORCEPROP 2 LAST CDS_LOCATION R3027
J 0
(-7575 -2725);
DISPLAY 1.021277 (-7575 -2725);
DISPLAY INVISIBLE (-7575 -2725);
FORCEPROP 2 LAST $SEC 1
J 0
(-7575 -2725);
DISPLAY 0.680851 (-7575 -2725);
PAINT MONO (-7575 -2725);
DISPLAY INVISIBLE (-7575 -2725);
FORCEPROP 2 LAST CDS_SEC 1
J 0
(-7575 -2725);
DISPLAY 1.021277 (-7575 -2725);
DISPLAY INVISIBLE (-7575 -2725);
FORCEADD Q_RES..2
(-7850 -2950);
FORCEPROP 1 LAST PART_NUMBER CS21002FB06
J 0
(-7810 -3125);
DISPLAY 0.510638 (-7810 -3125);
DISPLAY INVISIBLE (-7810 -3125);
FORCEPROP 1 LAST VALUE 1K
J 0
(-7805 -2875);
DISPLAY 0.510638 (-7805 -2875);
FORCEPROP 1 LAST WATTAGE 1/16W
J 0
(-7810 -2975);
DISPLAY 0.510638 (-7810 -2975);
FORCEPROP 1 LAST TOLERANCE 1%
J 0
(-7805 -2925);
DISPLAY 0.510638 (-7805 -2925);
FORCEPROP 1 LAST MATERIAL CHIP
J 0
(-7810 -3025);
DISPLAY 0.510638 (-7810 -3025);
FORCEPROP 1 LAST PACK_TYPE 0402LF
J 0
(-7810 -3075);
DISPLAY 0.510638 (-7810 -3075);
FORCEPROP 1 LAST $LOCATION R3026
J 0
(-7805 -2825);
DISPLAY 0.978723 (-7805 -2825);
FORCEPROP 1 LASTPIN (-7850 -2850) $PN 1
J 0
(-7845 -2888);
DISPLAY 0.787234 (-7845 -2888);
FORCEPROP 1 LASTPIN (-7850 -3050) $PN 2
J 0
(-7845 -3040);
DISPLAY 0.787234 (-7845 -3040);
FORCEPROP 2 LAST CDS_LIB pure_quanta
J 0
(-7850 -2950);
PAINT MONO (-7850 -2950);
DISPLAY INVISIBLE (-7850 -2950);
FORCEPROP 1 LAST PATH I106
J 0
(-7800 -2775);
DISPLAY 0.978723 (-7800 -2775);
PAINT WHITE (-7800 -2775);
DISPLAY INVISIBLE (-7800 -2775);
FORCEPROP 2 LAST CDS_LOCATION R3026
J 0
(-7800 -2725);
DISPLAY 1.021277 (-7800 -2725);
DISPLAY INVISIBLE (-7800 -2725);
FORCEPROP 2 LAST $SEC 1
J 0
(-7800 -2725);
DISPLAY 0.680851 (-7800 -2725);
PAINT MONO (-7800 -2725);
DISPLAY INVISIBLE (-7800 -2725);
FORCEPROP 2 LAST CDS_SEC 1
J 0
(-7800 -2725);
DISPLAY 1.021277 (-7800 -2725);
DISPLAY INVISIBLE (-7800 -2725);
FORCEADD UNIVERSAL_GND..1
(-8175 -2975);
FORCEPROP 3 LASTPIN (-8175 -2925) SIG_NAME GND\g
J 0
(-8165 -2915);
DISPLAY 0.659574 (-8165 -2915);
PAINT MONO (-8165 -2915);
DISPLAY INVISIBLE (-8165 -2915);
FORCEPROP 2 LAST CDS_LIB logical_power
J 0
(-8175 -2975);
PAINT MONO (-8175 -2975);
DISPLAY INVISIBLE (-8175 -2975);
FORCEPROP 1 LAST HDL_POWER GND
J 1
(-8150 -3050);
DISPLAY 0.872340 (-8150 -3050);
PAINT GREEN (-8150 -3050);
DISPLAY INVISIBLE (-8150 -3050);
FORCEPROP 1 LAST PATH I107
J 0
(-8100 -2975);
DISPLAY 0.872340 (-8100 -2975);
PAINT AQUA (-8100 -2975);
DISPLAY INVISIBLE (-8100 -2975);
FORCEADD NC7SB3157..1
R 2
(-8600 -2475);
FORCEPROP 1 LAST PART_NUMBER ALSB3157000
J 2
(-8473 -2315);
DISPLAY 0.723404 (-8473 -2315);
PAINT GREEN (-8473 -2315);
DISPLAY INVISIBLE (-8473 -2315);
FORCEPROP 1 LAST MATERIAL IC
J 2
(-8473 -2395);
DISPLAY 0.723404 (-8473 -2395);
PAINT GREEN (-8473 -2395);
FORCEPROP 1 LAST VALUE NC7SB3157P6X
J 2
(-8473 -2155);
DISPLAY 0.723404 (-8473 -2155);
PAINT GREEN (-8473 -2155);
FORCEPROP 1 LAST $LOCATION U85
J 2
(-8473 -2235);
DISPLAY 0.723404 (-8473 -2235);
PAINT GREEN (-8473 -2235);
FORCEPROP 1 LASTPIN (-8900 -2575) $PN 4
J 2
(-8790 -2572);
DISPLAY 0.659574 (-8790 -2572);
PAINT GREEN (-8790 -2572);
FORCEPROP 1 LASTPIN (-8300 -2575) $PN 3
J 0
(-8410 -2572);
DISPLAY 0.659574 (-8410 -2572);
PAINT GREEN (-8410 -2572);
FORCEPROP 1 LASTPIN (-8300 -2475) $PN 1
J 0
(-8410 -2472);
DISPLAY 0.659574 (-8410 -2472);
PAINT GREEN (-8410 -2472);
FORCEPROP 1 LASTPIN (-8300 -2525) $PN 2
J 0
(-8410 -2522);
DISPLAY 0.659574 (-8410 -2522);
PAINT GREEN (-8410 -2522);
FORCEPROP 1 LASTPIN (-8900 -2475) $PN 6
J 2
(-8790 -2472);
DISPLAY 0.659574 (-8790 -2472);
PAINT GREEN (-8790 -2472);
FORCEPROP 1 LASTPIN (-8900 -2525) $PN 5
J 2
(-8790 -2522);
DISPLAY 0.659574 (-8790 -2522);
PAINT GREEN (-8790 -2522);
FORCEPROP 0 LAST PATH I109
J 0
(-8450 -2100);
DISPLAY 1.021277 (-8450 -2100);
DISPLAY INVISIBLE (-8450 -2100);
FORCEPROP 1 LAST CDS_LMAN_SYM_OUTLINE -150,50,150,-150
J 2
(-8600 -2475);
DISPLAY 0.468085 (-8600 -2475);
PAINT GREEN (-8600 -2475);
DISPLAY INVISIBLE (-8600 -2475);
FORCEPROP 2 LAST CDS_LIB pure_quanta
J 2
(-8600 -2475);
PAINT MONO (-8600 -2475);
DISPLAY INVISIBLE (-8600 -2475);
FORCEPROP 1 LAST PACK_TYPE SMLF
J 2
(-8600 -2725);
DISPLAY 0.723404 (-8600 -2725);
PAINT GREEN (-8600 -2725);
DISPLAY INVISIBLE (-8600 -2725);
FORCEPROP 0 LAST MANUF_PN NC7SB3157P6X
J 2
(-8475 -2050);
DISPLAY 0.808511 (-8475 -2050);
DISPLAY INVISIBLE (-8475 -2050);
FORCEPROP 1 LAST $LOCATION U85
J 0
(-8475 -1950);
DISPLAY 1.021277 (-8475 -1950);
DISPLAY INVISIBLE (-8475 -1950);
FORCEPROP 2 LAST CDS_LOCATION U85
J 0
(-8475 -1950);
DISPLAY 1.021277 (-8475 -1950);
DISPLAY INVISIBLE (-8475 -1950);
FORCEPROP 2 LAST $SEC 1
J 0
(-8475 -1950);
DISPLAY 0.680851 (-8475 -1950);
PAINT MONO (-8475 -1950);
DISPLAY INVISIBLE (-8475 -1950);
FORCEPROP 2 LAST CDS_SEC 1
J 0
(-8475 -1950);
DISPLAY 1.021277 (-8475 -1950);
DISPLAY INVISIBLE (-8475 -1950);
FORCEADD Q_CAP..1
R 2
(-9175 -2075);
FORCEPROP 1 LAST PART_NUMBER CH5104KEB02
J 2
(-9225 -2225);
DISPLAY 0.510638 (-9225 -2225);
DISPLAY INVISIBLE (-9225 -2225);
FORCEPROP 1 LAST PACK_TYPE C0402
J 2
(-9225 -2275);
DISPLAY 0.510638 (-9225 -2275);
FORCEPROP 1 LAST MATERIAL X6S
J 2
(-9225 -2175);
DISPLAY 0.510638 (-9225 -2175);
FORCEPROP 1 LAST TOLERANCE 10%
J 2
(-9225 -2125);
DISPLAY 0.510638 (-9225 -2125);
FORCEPROP 1 LAST VALUE 1UF
J 2
(-9225 -2025);
DISPLAY 0.510638 (-9225 -2025);
FORCEPROP 1 LAST VOLTAGE 25V
J 2
(-9225 -2075);
DISPLAY 0.510638 (-9225 -2075);
FORCEPROP 1 LAST $LOCATION C1289
J 2
(-9225 -1975);
DISPLAY 0.978723 (-9225 -1975);
FORCEPROP 1 LASTPIN (-9175 -1975) $PN 1
J 2
(-9185 -1995);
DISPLAY 0.787234 (-9185 -1995);
FORCEPROP 1 LASTPIN (-9175 -2175) $PN 2
J 2
(-9185 -2195);
DISPLAY 0.787234 (-9185 -2195);
FORCEPROP 2 LAST CDS_LIB pure_quanta
J 2
(-9175 -2075);
PAINT MONO (-9175 -2075);
DISPLAY INVISIBLE (-9175 -2075);
FORCEPROP 1 LAST PATH I110
J 2
(-9225 -1925);
DISPLAY 0.978723 (-9225 -1925);
PAINT WHITE (-9225 -1925);
DISPLAY INVISIBLE (-9225 -1925);
FORCEPROP 1 LAST $LOCATION C1289
J 0
(-9225 -1875);
DISPLAY 1.021277 (-9225 -1875);
DISPLAY INVISIBLE (-9225 -1875);
FORCEPROP 2 LAST CDS_LOCATION C1289
J 0
(-9225 -1875);
DISPLAY 1.021277 (-9225 -1875);
DISPLAY INVISIBLE (-9225 -1875);
FORCEPROP 2 LAST $SEC 1
J 0
(-9225 -1875);
DISPLAY 0.680851 (-9225 -1875);
PAINT MONO (-9225 -1875);
DISPLAY INVISIBLE (-9225 -1875);
FORCEPROP 2 LAST CDS_SEC 1
J 0
(-9225 -1875);
DISPLAY 1.021277 (-9225 -1875);
DISPLAY INVISIBLE (-9225 -1875);
FORCEADD UNIVERSAL_POWER..1
(-9525 -1800);
FORCEPROP 3 LASTPIN (-9525 -1850) SIG_NAME P3V3_AUX\g
J 0
(-9515 -1840);
DISPLAY 0.659574 (-9515 -1840);
PAINT MONO (-9515 -1840);
DISPLAY INVISIBLE (-9515 -1840);
FORCEPROP 1 LAST HDL_POWER P3V3_AUX
J 1
(-9525 -1750);
DISPLAY 0.872340 (-9525 -1750);
PAINT GREEN (-9525 -1750);
FORCEPROP 2 LAST CDS_LIB logical_power
J 0
(-9525 -1800);
PAINT MONO (-9525 -1800);
DISPLAY INVISIBLE (-9525 -1800);
FORCEPROP 1 LAST PATH I111
J 0
(-9475 -1775);
DISPLAY 0.872340 (-9475 -1775);
PAINT AQUA (-9475 -1775);
DISPLAY INVISIBLE (-9475 -1775);
FORCEADD Q_CAP..1
R 2
(-9525 -2075);
FORCEPROP 1 LAST PART_NUMBER CH4104K1B00
J 2
(-9575 -2225);
DISPLAY 0.510638 (-9575 -2225);
DISPLAY INVISIBLE (-9575 -2225);
FORCEPROP 1 LAST TOLERANCE 10%
J 2
(-9575 -2125);
DISPLAY 0.510638 (-9575 -2125);
FORCEPROP 1 LAST VALUE 0.1UF
J 2
(-9575 -2025);
DISPLAY 0.510638 (-9575 -2025);
FORCEPROP 1 LAST VOLTAGE 25V
J 2
(-9575 -2075);
DISPLAY 0.510638 (-9575 -2075);
FORCEPROP 1 LAST PACK_TYPE 0402
J 2
(-9575 -2275);
DISPLAY 0.510638 (-9575 -2275);
FORCEPROP 1 LAST MATERIAL X7R
J 2
(-9575 -2175);
DISPLAY 0.510638 (-9575 -2175);
FORCEPROP 1 LAST $LOCATION C1288
J 2
(-9575 -1975);
DISPLAY 0.978723 (-9575 -1975);
FORCEPROP 1 LASTPIN (-9525 -1975) $PN 1
J 2
(-9535 -1995);
DISPLAY 0.787234 (-9535 -1995);
FORCEPROP 1 LASTPIN (-9525 -2175) $PN 2
J 2
(-9535 -2195);
DISPLAY 0.787234 (-9535 -2195);
FORCEPROP 2 LAST CDS_LIB pure_quanta
J 2
(-9525 -2075);
PAINT MONO (-9525 -2075);
DISPLAY INVISIBLE (-9525 -2075);
FORCEPROP 1 LAST PATH I112
J 2
(-9575 -1925);
DISPLAY 0.978723 (-9575 -1925);
PAINT WHITE (-9575 -1925);
DISPLAY INVISIBLE (-9575 -1925);
FORCEPROP 1 LAST $LOCATION C1288
J 0
(-9575 -1875);
DISPLAY 1.021277 (-9575 -1875);
DISPLAY INVISIBLE (-9575 -1875);
FORCEPROP 2 LAST CDS_LOCATION C1288
J 0
(-9575 -1875);
DISPLAY 1.021277 (-9575 -1875);
DISPLAY INVISIBLE (-9575 -1875);
FORCEPROP 2 LAST $SEC 1
J 0
(-9575 -1875);
DISPLAY 0.680851 (-9575 -1875);
PAINT MONO (-9575 -1875);
DISPLAY INVISIBLE (-9575 -1875);
FORCEPROP 2 LAST CDS_SEC 1
J 0
(-9575 -1875);
DISPLAY 1.021277 (-9575 -1875);
DISPLAY INVISIBLE (-9575 -1875);
FORCEADD UNIVERSAL_GND..1
(-9525 -2375);
FORCEPROP 3 LASTPIN (-9525 -2325) SIG_NAME GND\g
J 0
(-9515 -2315);
DISPLAY 0.659574 (-9515 -2315);
PAINT MONO (-9515 -2315);
DISPLAY INVISIBLE (-9515 -2315);
FORCEPROP 1 LAST HDL_POWER GND
J 1
(-9500 -2450);
DISPLAY 0.872340 (-9500 -2450);
PAINT GREEN (-9500 -2450);
DISPLAY INVISIBLE (-9500 -2450);
FORCEPROP 2 LAST CDS_LIB logical_power
J 0
(-9525 -2375);
PAINT MONO (-9525 -2375);
DISPLAY INVISIBLE (-9525 -2375);
FORCEPROP 1 LAST PATH I113
J 0
(-9450 -2375);
DISPLAY 0.872340 (-9450 -2375);
PAINT AQUA (-9450 -2375);
DISPLAY INVISIBLE (-9450 -2375);
FORCEADD OFFPAGE..1
(-9850 -2475);
FORCEPROP 2 LAST $XR0 214 
J 0
(-10132 -2475);
DISPLAY 0.638298 (-10132 -2475);
PAINT MONO (-10132 -2475);
FORCEPROP 2 LAST PATH I114
J 0
(-10125 -2425);
DISPLAY 1.021277 (-10125 -2425);
DISPLAY INVISIBLE (-10125 -2425);
FORCEPROP 2 LAST CDS_LIB standard
J 0
(-9850 -2475);
PAINT MONO (-9850 -2475);
DISPLAY INVISIBLE (-9850 -2475);
FORCEPROP 1 LAST OFFPAGE TRUE
J 0
(-9525 -2600);
DISPLAY 0.872340 (-9525 -2600);
PAINT GREEN (-9525 -2600);
DISPLAY INVISIBLE (-9525 -2600);
FORCEPROP 1 LAST COMMENT_BODY TRUE
J 0
(-9725 -2575);
DISPLAY 0.872340 (-9725 -2575);
PAINT GREEN (-9725 -2575);
DISPLAY INVISIBLE (-9725 -2575);
FORCEADD OFFPAGE..1
(-9850 -2575);
FORCEPROP 2 LAST $XR0 239 
J 0
(-10132 -2575);
DISPLAY 0.638298 (-10132 -2575);
PAINT MONO (-10132 -2575);
FORCEPROP 1 LAST COMMENT_BODY TRUE
J 0
(-9725 -2675);
DISPLAY 0.872340 (-9725 -2675);
PAINT GREEN (-9725 -2675);
DISPLAY INVISIBLE (-9725 -2675);
FORCEPROP 1 LAST OFFPAGE TRUE
J 0
(-9525 -2700);
DISPLAY 0.872340 (-9525 -2700);
PAINT GREEN (-9525 -2700);
DISPLAY INVISIBLE (-9525 -2700);
FORCEPROP 2 LAST CDS_LIB standard
J 0
(-9850 -2575);
PAINT MONO (-9850 -2575);
DISPLAY INVISIBLE (-9850 -2575);
FORCEPROP 2 LAST PATH I115
J 0
(-10125 -2525);
DISPLAY 1.021277 (-10125 -2525);
DISPLAY INVISIBLE (-10125 -2525);
FORCEADD Q_RES..2
(-9725 -2800);
FORCEPROP 1 LAST PART_NUMBER CS21002FB06
J 0
(-9685 -2975);
DISPLAY 0.510638 (-9685 -2975);
DISPLAY INVISIBLE (-9685 -2975);
FORCEPROP 1 LAST VALUE 1K
J 0
(-9680 -2725);
DISPLAY 0.510638 (-9680 -2725);
FORCEPROP 1 LAST TOLERANCE 1%
J 0
(-9680 -2775);
DISPLAY 0.510638 (-9680 -2775);
FORCEPROP 1 LAST MATERIAL CHIP
J 0
(-9685 -2875);
DISPLAY 0.510638 (-9685 -2875);
FORCEPROP 1 LAST PACK_TYPE 0402LF
J 0
(-9685 -2925);
DISPLAY 0.510638 (-9685 -2925);
FORCEPROP 1 LAST WATTAGE 1/16W
J 0
(-9685 -2825);
DISPLAY 0.510638 (-9685 -2825);
FORCEPROP 1 LAST $LOCATION R1365
J 0
(-9680 -2675);
DISPLAY 0.978723 (-9680 -2675);
FORCEPROP 1 LASTPIN (-9725 -2700) $PN 1
J 0
(-9720 -2738);
DISPLAY 0.787234 (-9720 -2738);
FORCEPROP 1 LASTPIN (-9725 -2900) $PN 2
J 0
(-9720 -2890);
DISPLAY 0.787234 (-9720 -2890);
FORCEPROP 2 LAST CDS_LIB pure_quanta
J 0
(-9725 -2800);
PAINT MONO (-9725 -2800);
DISPLAY INVISIBLE (-9725 -2800);
FORCEPROP 1 LAST PATH I116
J 0
(-9675 -2625);
DISPLAY 0.978723 (-9675 -2625);
PAINT WHITE (-9675 -2625);
DISPLAY INVISIBLE (-9675 -2625);
FORCEPROP 2 LAST CDS_LOCATION R1365
J 0
(-9675 -2575);
DISPLAY 1.021277 (-9675 -2575);
DISPLAY INVISIBLE (-9675 -2575);
FORCEPROP 2 LAST $SEC 1
J 0
(-9675 -2575);
DISPLAY 0.680851 (-9675 -2575);
PAINT MONO (-9675 -2575);
DISPLAY INVISIBLE (-9675 -2575);
FORCEPROP 2 LAST CDS_SEC 1
J 0
(-9675 -2575);
DISPLAY 1.021277 (-9675 -2575);
DISPLAY INVISIBLE (-9675 -2575);
FORCEADD UNIVERSAL_GND..1
(-9725 -3000);
FORCEPROP 3 LASTPIN (-9725 -2950) SIG_NAME GND\g
J 0
(-9715 -2940);
DISPLAY 0.659574 (-9715 -2940);
PAINT MONO (-9715 -2940);
DISPLAY INVISIBLE (-9715 -2940);
FORCEPROP 2 LAST CDS_LIB logical_power
J 0
(-9725 -3000);
PAINT MONO (-9725 -3000);
DISPLAY INVISIBLE (-9725 -3000);
FORCEPROP 1 LAST HDL_POWER GND
J 1
(-9700 -3075);
DISPLAY 0.872340 (-9700 -3075);
PAINT GREEN (-9700 -3075);
DISPLAY INVISIBLE (-9700 -3075);
FORCEPROP 1 LAST PATH I117
J 0
(-9650 -3000);
DISPLAY 0.872340 (-9650 -3000);
PAINT AQUA (-9650 -3000);
DISPLAY INVISIBLE (-9650 -3000);
FORCEADD UNIVERSAL_POWER..1
(-8175 -1000);
FORCEPROP 3 LASTPIN (-8175 -1050) SIG_NAME P3V3_AUX\g
J 0
(-8165 -1040);
DISPLAY 0.659574 (-8165 -1040);
PAINT MONO (-8165 -1040);
DISPLAY INVISIBLE (-8165 -1040);
FORCEPROP 1 LAST HDL_POWER P3V3_AUX
J 1
(-8175 -950);
DISPLAY 0.702128 (-8175 -950);
PAINT GREEN (-8175 -950);
FORCEPROP 1 LAST PATH I118
J 0
(-8125 -975);
DISPLAY 0.872340 (-8125 -975);
PAINT AQUA (-8125 -975);
DISPLAY INVISIBLE (-8125 -975);
FORCEPROP 2 LAST CDS_LIB logical_power
J 0
(-8175 -1000);
DISPLAY INVISIBLE (-8175 -1000);
FORCEADD OFFPAGE..5
(-8475 -1500);
FORCEPROP 2 LAST $XR0 215 
J 0
(-8730 -1500);
DISPLAY 0.638298 (-8730 -1500);
PAINT MONO (-8730 -1500);
FORCEPROP 2 LAST PATH I119
J 0
(-8750 -1450);
DISPLAY 1.021277 (-8750 -1450);
DISPLAY INVISIBLE (-8750 -1450);
FORCEPROP 2 LAST CDS_LIB standard
J 0
(-8475 -1500);
DISPLAY INVISIBLE (-8475 -1500);
FORCEPROP 1 LAST OFFPAGE TRUE
J 0
(-8150 -1625);
DISPLAY 0.872340 (-8150 -1625);
DISPLAY INVISIBLE (-8150 -1625);
FORCEPROP 1 LAST COMMENT_BODY TRUE
J 0
(-8375 -1575);
DISPLAY 0.872340 (-8375 -1575);
PAINT GREEN (-8375 -1575);
DISPLAY INVISIBLE (-8375 -1575);
FORCEADD 74CBTLV3126PW..1
(-6025 -2450);
FORCEPROP 1 LAST PART_NUMBER AL003126K08
J 0
(-6273 -2042);
DISPLAY 0.723404 (-6273 -2042);
PAINT GREEN (-6273 -2042);
DISPLAY INVISIBLE (-6273 -2042);
FORCEPROP 2 LAST PART_TYPE SMLF
J 0
(-6250 -1900);
DISPLAY 1.021277 (-6250 -1900);
FORCEPROP 2 LAST VALUE 74CBTLV3126PW
J 0
(-6250 -1950);
DISPLAY 1.021277 (-6250 -1950);
FORCEPROP 1 LAST MATERIAL IC
J 0
(-6273 -2097);
DISPLAY 0.723404 (-6273 -2097);
PAINT GREEN (-6273 -2097);
FORCEPROP 1 LAST $LOCATION U86
J 0
(-6273 -1992);
DISPLAY 0.723404 (-6273 -1992);
PAINT GREEN (-6273 -1992);
FORCEPROP 2 LASTPIN (-6425 -2700) $PN 2
J 2
(-6435 -2690);
DISPLAY 0.808511 (-6435 -2690);
FORCEPROP 2 LASTPIN (-5625 -2700) $PN 3
J 0
(-5615 -2690);
DISPLAY 0.808511 (-5615 -2690);
FORCEPROP 2 LASTPIN (-6425 -2750) $PN 1
J 2
(-6435 -2740);
DISPLAY 0.808511 (-6435 -2740);
FORCEPROP 2 LASTPIN (-6425 -2550) $PN 5
J 2
(-6435 -2540);
DISPLAY 0.808511 (-6435 -2540);
FORCEPROP 2 LASTPIN (-5625 -2550) $PN 6
J 0
(-5615 -2540);
DISPLAY 0.808511 (-5615 -2540);
FORCEPROP 2 LASTPIN (-6425 -2600) $PN 4
J 2
(-6435 -2590);
DISPLAY 0.808511 (-6435 -2590);
FORCEPROP 2 LASTPIN (-6425 -2400) $PN 9
J 2
(-6435 -2390);
DISPLAY 0.808511 (-6435 -2390);
FORCEPROP 2 LASTPIN (-5625 -2400) $PN 8
J 0
(-5615 -2390);
DISPLAY 0.808511 (-5615 -2390);
FORCEPROP 2 LASTPIN (-6425 -2450) $PN 10
J 2
(-6435 -2440);
DISPLAY 0.808511 (-6435 -2440);
FORCEPROP 2 LASTPIN (-6425 -2250) $PN 12
J 2
(-6435 -2240);
DISPLAY 0.808511 (-6435 -2240);
FORCEPROP 2 LASTPIN (-5625 -2250) $PN 11
J 0
(-5615 -2240);
DISPLAY 0.808511 (-5615 -2240);
FORCEPROP 2 LASTPIN (-6425 -2300) $PN 13
J 2
(-6435 -2290);
DISPLAY 0.808511 (-6435 -2290);
FORCEPROP 2 LASTPIN (-5625 -2750) $PN 7
J 0
(-5615 -2740);
DISPLAY 0.808511 (-5615 -2740);
FORCEPROP 2 LASTPIN (-5625 -2200) $PN 14
J 0
(-5615 -2190);
DISPLAY 0.808511 (-5615 -2190);
FORCEPROP 2 LAST CDS_LIB pure_quanta
J 0
(-6025 -2450);
PAINT MONO (-6025 -2450);
DISPLAY INVISIBLE (-6025 -2450);
FORCEPROP 1 LAST NEEDS_NO_SIZE TRUE
J 0
(-5775 -2760);
DISPLAY 0.723404 (-5775 -2760);
PAINT GREEN (-5775 -2760);
DISPLAY INVISIBLE (-5775 -2760);
FORCEPROP 1 LAST CDS_LMAN_SYM_OUTLINE -250,350,250,-350
J 0
(-6025 -2450);
DISPLAY 0.468085 (-6025 -2450);
PAINT GREEN (-6025 -2450);
DISPLAY INVISIBLE (-6025 -2450);
FORCEPROP 1 LAST PATH I84
J 0
(-5775 -2800);
DISPLAY 0.723404 (-5775 -2800);
PAINT GREEN (-5775 -2800);
DISPLAY INVISIBLE (-5775 -2800);
FORCEPROP 1 LAST $LOCATION U86
J 2
(-6250 -1850);
DISPLAY 1.021277 (-6250 -1850);
DISPLAY INVISIBLE (-6250 -1850);
FORCEPROP 2 LAST CDS_LOCATION U86
J 0
(-6250 -1850);
DISPLAY 1.021277 (-6250 -1850);
DISPLAY INVISIBLE (-6250 -1850);
FORCEPROP 2 LAST $SEC 1
J 2
(-6250 -1850);
DISPLAY 0.680851 (-6250 -1850);
PAINT MONO (-6250 -1850);
DISPLAY INVISIBLE (-6250 -1850);
FORCEPROP 2 LAST CDS_SEC 1
J 2
(-6250 -1850);
DISPLAY 1.021277 (-6250 -1850);
DISPLAY INVISIBLE (-6250 -1850);
FORCEADD OFFPAGE..2
(-2775 -2400);
FORCEPROP 2 LAST $XR1 182 
J 0
(-2466 -2400);
DISPLAY 0.638298 (-2466 -2400);
PAINT MONO (-2466 -2400);
FORCEPROP 2 LAST $XR0 131 
J 0
(-2586 -2400);
DISPLAY 0.638298 (-2586 -2400);
PAINT MONO (-2586 -2400);
FORCEPROP 2 LAST CDS_LIB standard
J 0
(-2775 -2400);
PAINT MONO (-2775 -2400);
DISPLAY INVISIBLE (-2775 -2400);
FORCEPROP 2 LAST PATH I85
J 0
(-2425 -2350);
DISPLAY 1.021277 (-2425 -2350);
DISPLAY INVISIBLE (-2425 -2350);
FORCEPROP 1 LAST OFFPAGE TRUE
J 0
(-2450 -2525);
DISPLAY 0.872340 (-2450 -2525);
PAINT GREEN (-2450 -2525);
DISPLAY INVISIBLE (-2450 -2525);
FORCEPROP 1 LAST COMMENT_BODY TRUE
J 0
(-2820 -2495);
DISPLAY 0.872340 (-2820 -2495);
PAINT GREEN (-2820 -2495);
DISPLAY INVISIBLE (-2820 -2495);
FORCEADD OFFPAGE..2
(-2775 -2550);
FORCEPROP 2 LAST $XR3 44 
J 0
(-2256 -2550);
DISPLAY 0.638298 (-2256 -2550);
PAINT MONO (-2256 -2550);
FORCEPROP 2 LAST $XR2 13 
J 0
(-2346 -2550);
DISPLAY 0.638298 (-2346 -2550);
PAINT MONO (-2346 -2550);
FORCEPROP 2 LAST $XR1 182 
J 0
(-2466 -2550);
DISPLAY 0.638298 (-2466 -2550);
PAINT MONO (-2466 -2550);
FORCEPROP 2 LAST $XR0 131 
J 0
(-2586 -2550);
DISPLAY 0.638298 (-2586 -2550);
PAINT MONO (-2586 -2550);
FORCEPROP 2 LAST CDS_LIB standard
J 0
(-2775 -2550);
PAINT MONO (-2775 -2550);
DISPLAY INVISIBLE (-2775 -2550);
FORCEPROP 1 LAST OFFPAGE TRUE
J 0
(-2450 -2675);
DISPLAY 0.872340 (-2450 -2675);
PAINT GREEN (-2450 -2675);
DISPLAY INVISIBLE (-2450 -2675);
FORCEPROP 1 LAST COMMENT_BODY TRUE
J 0
(-2820 -2645);
DISPLAY 0.872340 (-2820 -2645);
PAINT GREEN (-2820 -2645);
DISPLAY INVISIBLE (-2820 -2645);
FORCEPROP 2 LAST PATH I86
J 0
(-2150 -2500);
DISPLAY 1.021277 (-2150 -2500);
DISPLAY INVISIBLE (-2150 -2500);
FORCEADD Q_RES..1
(-4350 -2400);
FORCEPROP 1 LAST PART_NUMBER CS00002JB13
J 0
(-4475 -2325);
DISPLAY 0.638298 (-4475 -2325);
DISPLAY INVISIBLE (-4475 -2325);
FORCEPROP 1 LAST TOLERANCE 5%
J 0
(-4175 -2400);
DISPLAY 0.638298 (-4175 -2400);
FORCEPROP 1 LAST VALUE 0
J 2
(-4200 -2400);
DISPLAY 0.638298 (-4200 -2400);
FORCEPROP 1 LAST PACK_TYPE 0402LF
J 0
(-4075 -2400);
DISPLAY 0.638298 (-4075 -2400);
FORCEPROP 1 LAST MATERIAL CHIP
J 0
(-4475 -2275);
DISPLAY 0.638298 (-4475 -2275);
FORCEPROP 1 LAST WATTAGE 1/16W
J 2
(-4175 -2275);
DISPLAY 0.638298 (-4175 -2275);
FORCEPROP 1 LAST $LOCATION R1349
J 0
(-4550 -2400);
DISPLAY 0.510638 (-4550 -2400);
FORCEPROP 1 LASTPIN (-4450 -2400) $PN 1
J 0
(-4438 -2388);
DISPLAY 0.787234 (-4438 -2388);
FORCEPROP 1 LASTPIN (-4250 -2400) $PN 2
J 0
(-4288 -2388);
DISPLAY 0.787234 (-4288 -2388);
FORCEPROP 2 LAST CDS_LIB pure_quanta
J 0
(-4350 -2400);
PAINT MONO (-4350 -2400);
DISPLAY INVISIBLE (-4350 -2400);
FORCEPROP 1 LAST PATH I87
J 0
(-4400 -2250);
DISPLAY 0.978723 (-4400 -2250);
PAINT WHITE (-4400 -2250);
DISPLAY INVISIBLE (-4400 -2250);
FORCEPROP 1 LAST $LOCATION R1349
J 0
(-4400 -2200);
DISPLAY 1.021277 (-4400 -2200);
DISPLAY INVISIBLE (-4400 -2200);
FORCEPROP 2 LAST CDS_LOCATION R1349
J 0
(-4400 -2200);
DISPLAY 1.021277 (-4400 -2200);
DISPLAY INVISIBLE (-4400 -2200);
FORCEPROP 2 LAST $SEC 1
J 0
(-4400 -2200);
DISPLAY 0.680851 (-4400 -2200);
PAINT MONO (-4400 -2200);
DISPLAY INVISIBLE (-4400 -2200);
FORCEPROP 2 LAST CDS_SEC 1
J 0
(-4400 -2200);
DISPLAY 1.021277 (-4400 -2200);
DISPLAY INVISIBLE (-4400 -2200);
FORCEADD Q_RES..1
(-4350 -2550);
FORCEPROP 1 LAST PART_NUMBER CS00002JB13
J 0
(-4475 -2325);
DISPLAY 0.638298 (-4475 -2325);
DISPLAY INVISIBLE (-4475 -2325);
FORCEPROP 1 LAST PACK_TYPE 0402LF
J 0
(-4075 -2550);
DISPLAY 0.638298 (-4075 -2550);
FORCEPROP 1 LAST VALUE 0
J 2
(-4200 -2550);
DISPLAY 0.638298 (-4200 -2550);
FORCEPROP 1 LAST TOLERANCE 5%
J 0
(-4175 -2550);
DISPLAY 0.638298 (-4175 -2550);
FORCEPROP 1 LAST $LOCATION R1348
J 0
(-4550 -2550);
DISPLAY 0.510638 (-4550 -2550);
FORCEPROP 1 LASTPIN (-4450 -2550) $PN 1
J 0
(-4438 -2538);
DISPLAY 0.787234 (-4438 -2538);
FORCEPROP 1 LASTPIN (-4250 -2550) $PN 2
J 0
(-4288 -2538);
DISPLAY 0.787234 (-4288 -2538);
FORCEPROP 2 LAST CDS_LIB pure_quanta
J 0
(-4350 -2550);
PAINT MONO (-4350 -2550);
DISPLAY INVISIBLE (-4350 -2550);
FORCEPROP 1 LAST MATERIAL CHIP
J 0
(-4475 -2275);
DISPLAY 0.638298 (-4475 -2275);
DISPLAY INVISIBLE (-4475 -2275);
FORCEPROP 1 LAST WATTAGE 1/16W
J 2
(-4175 -2275);
DISPLAY 0.638298 (-4175 -2275);
DISPLAY INVISIBLE (-4175 -2275);
FORCEPROP 1 LAST PATH I88
J 0
(-4400 -2400);
DISPLAY 0.978723 (-4400 -2400);
PAINT WHITE (-4400 -2400);
DISPLAY INVISIBLE (-4400 -2400);
FORCEPROP 1 LAST $LOCATION R1348
J 0
(-4400 -2350);
DISPLAY 1.021277 (-4400 -2350);
DISPLAY INVISIBLE (-4400 -2350);
FORCEPROP 2 LAST CDS_LOCATION R1348
J 0
(-4400 -2350);
DISPLAY 1.021277 (-4400 -2350);
DISPLAY INVISIBLE (-4400 -2350);
FORCEPROP 2 LAST $SEC 1
J 0
(-4400 -2350);
DISPLAY 0.680851 (-4400 -2350);
PAINT MONO (-4400 -2350);
DISPLAY INVISIBLE (-4400 -2350);
FORCEPROP 2 LAST CDS_SEC 1
J 0
(-4400 -2350);
DISPLAY 1.021277 (-4400 -2350);
DISPLAY INVISIBLE (-4400 -2350);
FORCEADD UNIVERSAL_POWER..1
(-5475 -1600);
FORCEPROP 3 LASTPIN (-5475 -1650) SIG_NAME P3V3_AUX\g
J 0
(-5465 -1640);
DISPLAY 0.659574 (-5465 -1640);
PAINT MONO (-5465 -1640);
DISPLAY INVISIBLE (-5465 -1640);
FORCEPROP 1 LAST HDL_POWER P3V3_AUX
J 1
(-5475 -1550);
DISPLAY 0.872340 (-5475 -1550);
PAINT GREEN (-5475 -1550);
FORCEPROP 2 LAST CDS_LIB logical_power
J 0
(-5475 -1600);
PAINT MONO (-5475 -1600);
DISPLAY INVISIBLE (-5475 -1600);
FORCEPROP 1 LAST PATH I89
J 0
(-5425 -1575);
DISPLAY 0.872340 (-5425 -1575);
PAINT AQUA (-5425 -1575);
DISPLAY INVISIBLE (-5425 -1575);
FORCEADD Q_CAP..1
(-5275 -1950);
FORCEPROP 1 LAST PART_NUMBER CH4104K1B00
J 0
(-5225 -2100);
DISPLAY 0.510638 (-5225 -2100);
DISPLAY INVISIBLE (-5225 -2100);
FORCEPROP 1 LAST PACK_TYPE 0402
J 0
(-5225 -2150);
DISPLAY 0.510638 (-5225 -2150);
FORCEPROP 1 LAST VALUE 0.1UF
J 0
(-5225 -1900);
DISPLAY 0.510638 (-5225 -1900);
FORCEPROP 1 LAST VOLTAGE 25V
J 0
(-5225 -1950);
DISPLAY 0.510638 (-5225 -1950);
FORCEPROP 1 LAST MATERIAL X7R
J 0
(-5225 -2050);
DISPLAY 0.510638 (-5225 -2050);
FORCEPROP 1 LAST TOLERANCE 10%
J 0
(-5225 -2000);
DISPLAY 0.510638 (-5225 -2000);
FORCEPROP 1 LAST $LOCATION C1292
J 0
(-5225 -1850);
DISPLAY 0.978723 (-5225 -1850);
FORCEPROP 1 LASTPIN (-5275 -1850) $PN 1
J 0
(-5265 -1870);
DISPLAY 0.787234 (-5265 -1870);
FORCEPROP 1 LASTPIN (-5275 -2050) $PN 2
J 0
(-5265 -2070);
DISPLAY 0.787234 (-5265 -2070);
FORCEPROP 2 LAST CDS_LIB pure_quanta
J 2
(-5275 -1950);
PAINT MONO (-5275 -1950);
DISPLAY INVISIBLE (-5275 -1950);
FORCEPROP 1 LAST PATH I90
J 0
(-5225 -1800);
DISPLAY 0.978723 (-5225 -1800);
PAINT WHITE (-5225 -1800);
DISPLAY INVISIBLE (-5225 -1800);
FORCEPROP 1 LAST $LOCATION C1292
J 2
(-5225 -1750);
DISPLAY 1.021277 (-5225 -1750);
DISPLAY INVISIBLE (-5225 -1750);
FORCEPROP 2 LAST CDS_LOCATION C1292
J 0
(-5225 -1750);
DISPLAY 1.021277 (-5225 -1750);
DISPLAY INVISIBLE (-5225 -1750);
FORCEPROP 2 LAST $SEC 1
J 2
(-5225 -1750);
DISPLAY 0.680851 (-5225 -1750);
PAINT MONO (-5225 -1750);
DISPLAY INVISIBLE (-5225 -1750);
FORCEPROP 2 LAST CDS_SEC 1
J 2
(-5225 -1750);
DISPLAY 1.021277 (-5225 -1750);
DISPLAY INVISIBLE (-5225 -1750);
FORCEADD UNIVERSAL_GND..1
(-5275 -2175);
FORCEPROP 3 LASTPIN (-5275 -2125) SIG_NAME GND\g
J 0
(-5265 -2115);
DISPLAY 0.659574 (-5265 -2115);
PAINT MONO (-5265 -2115);
DISPLAY INVISIBLE (-5265 -2115);
FORCEPROP 2 LAST CDS_LIB logical_power
J 0
(-5275 -2175);
PAINT MONO (-5275 -2175);
DISPLAY INVISIBLE (-5275 -2175);
FORCEPROP 1 LAST HDL_POWER GND
J 1
(-5250 -2250);
DISPLAY 0.872340 (-5250 -2250);
PAINT GREEN (-5250 -2250);
DISPLAY INVISIBLE (-5250 -2250);
FORCEPROP 1 LAST PATH I91
J 0
(-5200 -2175);
DISPLAY 0.872340 (-5200 -2175);
PAINT AQUA (-5200 -2175);
DISPLAY INVISIBLE (-5200 -2175);
FORCEADD UNIVERSAL_GND..1
(-5475 -2950);
FORCEPROP 3 LASTPIN (-5475 -2900) SIG_NAME GND\g
J 0
(-5465 -2890);
DISPLAY 0.659574 (-5465 -2890);
PAINT MONO (-5465 -2890);
DISPLAY INVISIBLE (-5465 -2890);
FORCEPROP 2 LAST CDS_LIB logical_power
J 0
(-5475 -2950);
PAINT MONO (-5475 -2950);
DISPLAY INVISIBLE (-5475 -2950);
FORCEPROP 1 LAST HDL_POWER GND
J 1
(-5450 -3025);
DISPLAY 0.872340 (-5450 -3025);
PAINT GREEN (-5450 -3025);
DISPLAY INVISIBLE (-5450 -3025);
FORCEPROP 1 LAST PATH I92
J 0
(-5400 -2950);
DISPLAY 0.872340 (-5400 -2950);
PAINT AQUA (-5400 -2950);
DISPLAY INVISIBLE (-5400 -2950);
FORCEADD UNIVERSAL_POWER..1
(-7225 -1125);
FORCEPROP 3 LASTPIN (-7225 -1175) SIG_NAME P1V05_PCH_AUX\g
J 0
(-7215 -1165);
DISPLAY 0.659574 (-7215 -1165);
PAINT MONO (-7215 -1165);
DISPLAY INVISIBLE (-7215 -1165);
FORCEPROP 1 LAST HDL_POWER P1V05_PCH_AUX
J 1
(-7225 -1075);
DISPLAY 0.872340 (-7225 -1075);
PAINT GREEN (-7225 -1075);
FORCEPROP 1 LAST PATH I93
J 0
(-7175 -1100);
DISPLAY 0.872340 (-7175 -1100);
PAINT AQUA (-7175 -1100);
DISPLAY INVISIBLE (-7175 -1100);
FORCEPROP 2 LAST CDS_LIB logical_power
J 0
(-7225 -1125);
PAINT MONO (-7225 -1125);
DISPLAY INVISIBLE (-7225 -1125);
FORCEADD UNIVERSAL_GND..1
(-7050 -2350);
FORCEPROP 3 LASTPIN (-7050 -2300) SIG_NAME GND\g
J 0
(-7040 -2290);
DISPLAY 0.659574 (-7040 -2290);
PAINT MONO (-7040 -2290);
DISPLAY INVISIBLE (-7040 -2290);
FORCEPROP 1 LAST HDL_POWER GND
J 1
(-7025 -2425);
DISPLAY 0.872340 (-7025 -2425);
PAINT GREEN (-7025 -2425);
DISPLAY INVISIBLE (-7025 -2425);
FORCEPROP 2 LAST CDS_LIB logical_power
J 0
(-7050 -2350);
PAINT MONO (-7050 -2350);
DISPLAY INVISIBLE (-7050 -2350);
FORCEPROP 1 LAST PATH I94
J 0
(-6975 -2350);
DISPLAY 0.872340 (-6975 -2350);
PAINT AQUA (-6975 -2350);
DISPLAY INVISIBLE (-6975 -2350);
FORCEADD Q_CAP..1
(-7050 -2075);
FORCEPROP 1 LAST PART_NUMBER CH5104KEB02
J 0
(-7000 -2225);
DISPLAY 0.510638 (-7000 -2225);
DISPLAY INVISIBLE (-7000 -2225);
FORCEPROP 1 LAST PACK_TYPE C0402
J 0
(-7000 -2275);
DISPLAY 0.510638 (-7000 -2275);
FORCEPROP 1 LAST VALUE 1UF
J 0
(-7000 -2025);
DISPLAY 0.510638 (-7000 -2025);
FORCEPROP 1 LAST MATERIAL X6S
J 0
(-7000 -2175);
DISPLAY 0.510638 (-7000 -2175);
FORCEPROP 1 LAST VOLTAGE 25V
J 0
(-7000 -2075);
DISPLAY 0.510638 (-7000 -2075);
FORCEPROP 1 LAST TOLERANCE 10%
J 0
(-7000 -2125);
DISPLAY 0.510638 (-7000 -2125);
FORCEPROP 1 LAST $LOCATION C1293
J 0
(-7000 -1975);
DISPLAY 0.978723 (-7000 -1975);
FORCEPROP 1 LASTPIN (-7050 -1975) $PN 1
J 0
(-7040 -1995);
DISPLAY 0.787234 (-7040 -1995);
FORCEPROP 1 LASTPIN (-7050 -2175) $PN 2
J 0
(-7040 -2195);
DISPLAY 0.787234 (-7040 -2195);
FORCEPROP 2 LAST CDS_LIB pure_quanta
J 0
(-7050 -2075);
PAINT MONO (-7050 -2075);
DISPLAY INVISIBLE (-7050 -2075);
FORCEPROP 1 LAST PATH I95
J 0
(-7000 -1925);
DISPLAY 0.978723 (-7000 -1925);
PAINT WHITE (-7000 -1925);
DISPLAY INVISIBLE (-7000 -1925);
FORCEPROP 2 LAST CDS_LOCATION C1293
J 0
(-7000 -1875);
DISPLAY 1.021277 (-7000 -1875);
DISPLAY INVISIBLE (-7000 -1875);
FORCEPROP 2 LAST $SEC 1
J 0
(-7000 -1875);
DISPLAY 0.680851 (-7000 -1875);
PAINT MONO (-7000 -1875);
DISPLAY INVISIBLE (-7000 -1875);
FORCEPROP 2 LAST CDS_SEC 1
J 0
(-7000 -1875);
DISPLAY 1.021277 (-7000 -1875);
DISPLAY INVISIBLE (-7000 -1875);
FORCEADD MOSFET_N..1
(-7275 -1375);
FORCEPROP 1 LAST PART_NUMBER BAM138K0000
J 0
(-7128 -1464);
DISPLAY 0.574468 (-7128 -1464);
PAINT GREEN (-7128 -1464);
DISPLAY INVISIBLE (-7128 -1464);
FORCEPROP 1 LAST MATERIAL IC
J 0
(-7128 -1544);
DISPLAY 0.574468 (-7128 -1544);
PAINT GREEN (-7128 -1544);
FORCEPROP 1 LAST VALUE BSS138K
J 0
(-7128 -1304);
DISPLAY 0.574468 (-7128 -1304);
PAINT GREEN (-7128 -1304);
FORCEPROP 1 LAST $LOCATION U87
J 0
(-7128 -1384);
DISPLAY 0.574468 (-7128 -1384);
PAINT GREEN (-7128 -1384);
FORCEPROP 1 LASTPIN (-7225 -1275) $PN D
R 1
J 0
(-7225 -1282);
DISPLAY 0.659574 (-7225 -1282);
PAINT GREEN (-7225 -1282);
FORCEPROP 1 LASTPIN (-7375 -1475) $PN G
J 2
(-7365 -1472);
DISPLAY 0.659574 (-7365 -1472);
PAINT GREEN (-7365 -1472);
FORCEPROP 1 LASTPIN (-7225 -1575) $PN S
R 1
J 2
(-7225 -1562);
DISPLAY 0.659574 (-7225 -1562);
PAINT GREEN (-7225 -1562);
FORCEPROP 0 LAST MANUF_PN BSS138K
J 0
(-7100 -1500);
DISPLAY 0.808511 (-7100 -1500);
DISPLAY INVISIBLE (-7100 -1500);
FORCEPROP 1 LAST PACK_TYPE SMLF
J 0
(-7250 -1625);
DISPLAY 0.723404 (-7250 -1625);
PAINT GREEN (-7250 -1625);
DISPLAY INVISIBLE (-7250 -1625);
FORCEPROP 2 LAST CDS_LIB pure_quanta
J 0
(-7275 -1375);
PAINT MONO (-7275 -1375);
DISPLAY INVISIBLE (-7275 -1375);
FORCEPROP 1 LAST CDS_LMAN_SYM_OUTLINE -50,50,100,-150
J 0
(-7275 -1375);
DISPLAY 0.468085 (-7275 -1375);
PAINT GREEN (-7275 -1375);
DISPLAY INVISIBLE (-7275 -1375);
FORCEPROP 0 LAST PATH I96
J 0
(-7125 -1275);
DISPLAY 1.021277 (-7125 -1275);
DISPLAY INVISIBLE (-7125 -1275);
FORCEPROP 2 LAST CDS_LOCATION U87
J 0
(-7125 -1275);
DISPLAY 1.021277 (-7125 -1275);
DISPLAY INVISIBLE (-7125 -1275);
FORCEPROP 2 LAST $SEC 1
J 0
(-7125 -1275);
DISPLAY 0.680851 (-7125 -1275);
PAINT MONO (-7125 -1275);
DISPLAY INVISIBLE (-7125 -1275);
FORCEPROP 2 LAST CDS_SEC 1
J 0
(-7125 -1275);
DISPLAY 1.021277 (-7125 -1275);
DISPLAY INVISIBLE (-7125 -1275);
FORCEADD Q_RES..2
R 2
(-7225 -2075);
FORCEPROP 1 LAST PART_NUMBER CS31002FB08
J 2
(-7265 -2225);
DISPLAY 0.510638 (-7265 -2225);
DISPLAY INVISIBLE (-7265 -2225);
FORCEPROP 1 LAST TOLERANCE 1%
J 2
(-7270 -2075);
DISPLAY 0.510638 (-7270 -2075);
FORCEPROP 1 LAST PACK_TYPE 0402LF
J 2
(-7265 -2275);
DISPLAY 0.510638 (-7265 -2275);
FORCEPROP 1 LAST MATERIAL CHIP
J 2
(-7265 -2175);
DISPLAY 0.510638 (-7265 -2175);
FORCEPROP 1 LAST WATTAGE 1/16W
J 2
(-7265 -2125);
DISPLAY 0.510638 (-7265 -2125);
FORCEPROP 1 LAST VALUE 10K
J 2
(-7270 -2025);
DISPLAY 0.510638 (-7270 -2025);
FORCEPROP 1 LAST $LOCATION R1375
J 2
(-7270 -1975);
DISPLAY 0.978723 (-7270 -1975);
FORCEPROP 1 LASTPIN (-7225 -1975) $PN 1
J 2
(-7230 -2013);
DISPLAY 0.787234 (-7230 -2013);
FORCEPROP 1 LASTPIN (-7225 -2175) $PN 2
J 2
(-7230 -2165);
DISPLAY 0.787234 (-7230 -2165);
FORCEPROP 2 LAST CDS_LIB pure_quanta
J 2
(-7225 -2075);
PAINT MONO (-7225 -2075);
DISPLAY INVISIBLE (-7225 -2075);
FORCEPROP 1 LAST PATH I97
J 2
(-7275 -1900);
DISPLAY 0.978723 (-7275 -1900);
PAINT WHITE (-7275 -1900);
DISPLAY INVISIBLE (-7275 -1900);
FORCEPROP 2 LAST CDS_LOCATION R1375
J 0
(-7275 -1850);
DISPLAY 1.021277 (-7275 -1850);
DISPLAY INVISIBLE (-7275 -1850);
FORCEPROP 2 LAST $SEC 1
J 0
(-7275 -1850);
DISPLAY 0.680851 (-7275 -1850);
PAINT MONO (-7275 -1850);
DISPLAY INVISIBLE (-7275 -1850);
FORCEPROP 2 LAST CDS_SEC 1
J 0
(-7275 -1850);
DISPLAY 1.021277 (-7275 -1850);
DISPLAY INVISIBLE (-7275 -1850);
FORCEADD Q_RES..2
R 2
(-8175 -1250);
FORCEPROP 1 LAST PART_NUMBER CS11002FB07
J 2
(-8215 -1375);
DISPLAY 0.404255 (-8215 -1375);
DISPLAY INVISIBLE (-8215 -1375);
FORCEPROP 1 LAST WATTAGE 1/16W
J 2
(-8215 -1275);
DISPLAY 0.404255 (-8215 -1275);
FORCEPROP 1 LAST VALUE 100
J 2
(-8220 -1175);
DISPLAY 0.404255 (-8220 -1175);
FORCEPROP 1 LAST TOLERANCE 1%
J 2
(-8220 -1225);
DISPLAY 0.404255 (-8220 -1225);
FORCEPROP 1 LAST PACK_TYPE 0402LF
J 2
(-8215 -1425);
DISPLAY 0.404255 (-8215 -1425);
FORCEPROP 1 LAST MATERIAL CHIP
J 2
(-8215 -1325);
DISPLAY 0.404255 (-8215 -1325);
FORCEPROP 1 LAST $LOCATION R1370
J 2
(-8220 -1125);
DISPLAY 0.978723 (-8220 -1125);
FORCEPROP 1 LASTPIN (-8175 -1150) $PN 1
J 2
(-8180 -1188);
DISPLAY 0.787234 (-8180 -1188);
PAINT MONO (-8180 -1188);
FORCEPROP 1 LASTPIN (-8175 -1350) $PN 2
J 2
(-8180 -1340);
DISPLAY 0.787234 (-8180 -1340);
PAINT MONO (-8180 -1340);
FORCEPROP 2 LAST CDS_LIB pure_quanta
J 2
(-8175 -1250);
DISPLAY INVISIBLE (-8175 -1250);
FORCEPROP 1 LAST PATH I98
J 2
(-8225 -1075);
DISPLAY 0.978723 (-8225 -1075);
PAINT WHITE (-8225 -1075);
DISPLAY INVISIBLE (-8225 -1075);
FORCEPROP 2 LAST CDS_LOCATION R1370
J 2
(-8225 -1025);
DISPLAY 1.021277 (-8225 -1025);
DISPLAY INVISIBLE (-8225 -1025);
FORCEPROP 0 LAST $SEC 1
J 2
(-8225 -1075);
DISPLAY 0.680851 (-8225 -1075);
PAINT MONO (-8225 -1075);
DISPLAY INVISIBLE (-8225 -1075);
FORCEPROP 2 LAST CDS_SEC 1
J 2
(-8225 -1025);
DISPLAY 1.021277 (-8225 -1025);
DISPLAY INVISIBLE (-8225 -1025);
FORCEADD DNS..2
(-8175 -1800);
PAINT RED (-8175 -1800);
FORCEPROP 1 LAST COMMENT_BODY TRUE
R 1
J 0
(-8100 -2025);
DISPLAY 0.872340 (-8100 -2025);
PAINT GREEN (-8100 -2025);
DISPLAY INVISIBLE (-8100 -2025);
FORCEPROP 2 LAST CDS_LIB mstr_misc
J 0
(-8175 -1800);
DISPLAY INVISIBLE (-8175 -1800);
FORCEADD DESIGN_NOTE..1
(-9800 -3275);
FORCEPROP 0 LAST S2 FM_JTAG_TCK_MUX_SEL == HIGH ,  BMC TO PCH
J 0
(-10000 -3500);
DISPLAY 1.021277 (-10000 -3500);
PAINT SKYBLUE (-10000 -3500);
FORCEPROP 0 LAST S1 FM_JTAG_TCK_MUX_SEL == LOW (DEFAULT) ,  BMC TO CPU
J 0
(-10000 -3425);
DISPLAY 1.021277 (-10000 -3425);
PAINT SKYBLUE (-10000 -3425);
FORCEPROP 1 LAST COMMENT_BODY TRUE
J 0
(-9775 -3175);
DISPLAY 0.978723 (-9775 -3175);
DISPLAY INVISIBLE (-9775 -3175);
FORCEPROP 2 LAST CDS_LIB logical_power
J 0
(-9800 -3275);
PAINT MONO (-9800 -3275);
DISPLAY INVISIBLE (-9800 -3275);
FORCEADD DESIGN_NOTE..1
(-8675 -400);
FORCEPROP 0 LAST S3 FM_BMC_EN_DET
J 0
(-8875 -550);
DISPLAY 1.021277 (-8875 -550);
PAINT SKYBLUE (-8875 -550);
FORCEPROP 0 LAST S1 H: ENABLE  BMC XDP (DEFAULT)
J 0
(-8875 -625);
DISPLAY 1.021277 (-8875 -625);
PAINT SKYBLUE (-8875 -625);
FORCEPROP 0 LAST S2 L: DISABLE BMC XDP REMOTE DEBUG
J 0
(-8875 -700);
DISPLAY 1.021277 (-8875 -700);
PAINT SKYBLUE (-8875 -700);
FORCEPROP 2 LAST CDS_LIB logical_power
J 0
(-8675 -400);
DISPLAY INVISIBLE (-8675 -400);
FORCEPROP 1 LAST COMMENT_BODY TRUE
J 0
(-8650 -300);
DISPLAY 0.978723 (-8650 -300);
DISPLAY INVISIBLE (-8650 -300);
FORCEADD QUANTA_TITLE_BLOCK_C..1
(-1600 -5875);
FORCEPROP 0 LAST CDS_CON_LAST_MODIFIED Fri Aug 25 14:01:55 2023
J 0
(-3485 -5860);
PAINT MONO (-3485 -5860);
DISPLAY INVISIBLE (-3485 -5860);
FORCEPROP 2 LAST CUSTOM_TXT_CDS <XR_PAGE_TITLE>
J 0
(-9490 -625);
DISPLAY 0.638298 (-9490 -625);
PAINT PINK (-9490 -625);
DISPLAY INVISIBLE (-9490 -625);
FORCEPROP 2 LAST CUSTOM_TXT_CDS <CON_LAST_MODIFIED>
J 0
(-3485 -5860);
DISPLAY 0.978723 (-3485 -5860);
FORCEPROP 2 LAST CUSTOM_TXT_CDS <NAME_2>
J 0
(-4775 -5825);
FORCEPROP 2 LAST CUSTOM_TXT_CDS <NAME_1>
J 0
(-4775 -5700);
FORCEPROP 2 LAST CUSTOM_TXT_CDS <Q_NUMBER>
J 0
(-3003 -5772);
DISPLAY 1.212766 (-3003 -5772);
FORCEPROP 2 LAST CUSTOM_TXT_CDS <Q_PROJ>
J 0
(-3982 -5773);
DISPLAY 1.212766 (-3982 -5773);
FORCEPROP 2 LAST CUSTOM_TXT_CDS <Q_REV>
J 0
(-1784 -5772);
DISPLAY 1.212766 (-1784 -5772);
FORCEPROP 2 LAST CUSTOM_TXT_CDS <CON_PAGE_NUM> OF <CON_TOTAL_PAGES>
J 0
(-2046 -5857);
DISPLAY 0.978723 (-2046 -5857);
FORCEPROP 1 LAST Q_TITLE SPR & PCH - JTAG
J 0
(-10891 -5849);
DISPLAY 2.446809 (-10891 -5849);
PAINT GREEN (-10891 -5849);
FORCEPROP 1 LAST Q_DEPT 
J 1
(-5363 -5826);
DISPLAY 1.957447 (-5363 -5826);
PAINT GREEN (-5363 -5826);
FORCEPROP 2 LAST CDS_XR_PAGE_TITLE CR-134 : @S9S_MB_2U_LIB.S9S_MB_2U(SCH_1):PAGE134
J 0
(-9490 -625);
DISPLAY 0.638298 (-9490 -625);
PAINT PINK (-9490 -625);
DISPLAY INVISIBLE (-9490 -625);
FORCEPROP 2 LAST CDS_LIB pure_quanta
J 0
(-1600 -5875);
PAINT MONO (-1600 -5875);
DISPLAY INVISIBLE (-1600 -5875);
FORCEPROP 1 LAST CDS_LMAN_SYM_OUTLINE -9475,6775,100,-125
J 0
(-1600 -5875);
DISPLAY 0.468085 (-1600 -5875);
PAINT GREEN (-1600 -5875);
DISPLAY INVISIBLE (-1600 -5875);
FORCEPROP 2 LAST PAGE_BORDER TRUE
J 0
(-9490 -625);
DISPLAY 0.638298 (-9490 -625);
PAINT PINK (-9490 -625);
DISPLAY INVISIBLE (-9490 -625);
FORCEPROP 1 LAST COMMENT_BODY TRUE
J 0
(-1588 -5888);
DISPLAY 0.978723 (-1588 -5888);
PAINT GREEN (-1588 -5888);
DISPLAY INVISIBLE (-1588 -5888);
WIRE 16 -1 (-7225 -1175)(-7225 -1275);
WIRE 16 -1 (-5475 -1650)(-5475 -1775);
WIRE 16 -1 (-8175 -1150)(-8175 -1050);
WIRE 16 -1 (-9525 -1850)(-9525 -1900);
WIRE 16 -1 (-7050 -2250)(-7050 -2300);
WIRE 16 -1 (-7225 -2250)(-7050 -2250);
WIRE 16 -1 (-7050 -2175)(-7050 -2250);
WIRE 16 -1 (-5475 -2750)(-5475 -2900);
WIRE 16 -1 (-5625 -2750)(-5475 -2750);
FORCEPROP 0 LAST CDS_PHYS_NET_NAME GND
J 0
(-5550 -2703);
PAINT MONO (-5550 -2703);
DISPLAY INVISIBLE (-5550 -2703);
FORCEPROP 0 LAST VOLTAGE 3.3
J 0
(-5550 -2750);
PAINT MONO (-5550 -2750);
DISPLAY INVISIBLE (-5550 -2750);
FORCEPROP 0 LAST PHYS_NET_NAME GND
J 0
(-5550 -2703);
PAINT MONO (-5550 -2703);
DISPLAY INVISIBLE (-5550 -2703);
WIRE 16 -1 (-5275 -2050)(-5275 -2125);
WIRE 16 -1 (-9725 -2900)(-9725 -2950);
WIRE 16 -1 (-9525 -2300)(-9525 -2325);
WIRE 16 -1 (-9525 -2300)(-9175 -2300);
WIRE 16 -1 (-9525 -2175)(-9525 -2300);
WIRE 16 -1 (-8175 -2925)(-8175 -2525);
WIRE 16 -1 (-7400 -3125)(-7400 -3175);
WIRE 16 -1 (-7625 -3125)(-7400 -3125);
WIRE 16 -1 (-7400 -3050)(-7400 -3125);
WIRE 16 -1 (-8175 -1875)(-8175 -1975);
WIRE 16 -1 (-9725 -2475)(-9800 -2475);
WIRE 16 -1 (-9725 -2700)(-9725 -2475);
WIRE 16 -1 (-8900 -2475)(-9725 -2475);
FORCEPROP 0 LAST CDS_PHYS_NET_NAME FM_JTAG_TCK_MUX_SEL
J 0
(-9610 -2427);
PAINT MONO (-9610 -2427);
DISPLAY INVISIBLE (-9610 -2427);
FORCEPROP 2 LAST SIG_NAME FM_JTAG_TCK_MUX_SEL
J 0
(-9635 -2465);
DISPLAY 0.510638 (-9635 -2465);
PAINT WHITE (-9635 -2465);
WIRE 16 -1 (-7625 -3050)(-7625 -3125);
WIRE 16 -1 (-7850 -3125)(-7625 -3125);
WIRE 16 -1 (-7850 -3050)(-7850 -3125);
WIRE 16 -1 (-8300 -2475)(-7850 -2475);
FORCEPROP 0 LAST CDS_PHYS_NET_NAME JTAG_BMC_PCH_TCK
J 0
(-8110 -2427);
PAINT MONO (-8110 -2427);
DISPLAY INVISIBLE (-8110 -2427);
WIRE 16 -1 (-7850 -2850)(-7850 -2475);
WIRE 16 -1 (-7400 -2475)(-7850 -2475);
WIRE 16 -1 (-7400 -2475)(-7400 -2450);
FORCEPROP 2 LAST SIG_NAME JTAG_BMC_PCH_TCK
J 0
(-7285 -2440);
DISPLAY 0.510638 (-7285 -2440);
PAINT WHITE (-7285 -2440);
WIRE 16 -1 (-6425 -2450)(-7400 -2450);
WIRE 16 -1 (-8300 -2575)(-7625 -2575);
FORCEPROP 0 LAST CDS_PHYS_NET_NAME JTAG_BMC_CPU_TCK
J 0
(-8110 -2527);
PAINT MONO (-8110 -2527);
DISPLAY INVISIBLE (-8110 -2527);
WIRE 16 -1 (-7625 -2850)(-7625 -2575);
WIRE 16 -1 (-7400 -2575)(-7625 -2575);
WIRE 16 -1 (-7400 -2575)(-7400 -2600);
FORCEPROP 2 LAST SIG_NAME JTAG_BMC_CPU_TCK
J 0
(-7285 -2590);
DISPLAY 0.510638 (-7285 -2590);
PAINT WHITE (-7285 -2590);
WIRE 16 -1 (-6425 -2600)(-7400 -2600);
WIRE 16 -1 (-7400 -2850)(-7400 -2750);
WIRE 16 -1 (-6625 -2750)(-7400 -2750);
FORCEPROP 2 LAST SIG_NAME PD_JTAG_BMC_NTRST_N
J 0
(-7285 -2740);
DISPLAY 0.553191 (-7285 -2740);
PAINT WHITE (-7285 -2740);
WIRE 16 -1 (-6425 -2750)(-6625 -2750);
WIRE 16 -1 (-6625 -2750)(-6625 -2300);
WIRE 16 -1 (-6425 -2300)(-6625 -2300);
WIRE 16 -1 (-8175 -1500)(-8425 -1500);
WIRE 16 -1 (-8175 -1675)(-8175 -1500);
WIRE 16 -1 (-8175 -1500)(-8175 -1475);
WIRE 16 -1 (-7375 -1475)(-8175 -1475);
FORCEPROP 2 LAST SIG_NAME FM_REMOTE_DEBUG_DET_R
J 0
(-8135 -1465);
DISPLAY 0.638298 (-8135 -1465);
PAINT WHITE (-8135 -1465);
WIRE 16 -1 (-8175 -1350)(-8175 -1475);
WIRE 16 -1 (-7225 -2175)(-7225 -2250);
WIRE 16 -1 (-7225 -1975)(-7225 -1900);
WIRE 16 -1 (-7225 -1900)(-7225 -1575);
WIRE 16 -1 (-7225 -1900)(-7050 -1900);
FORCEPROP 2 LAST SIG_NAME FM_BMC_EN_DET
J 0
(-7035 -1890);
DISPLAY 0.446809 (-7035 -1890);
PAINT WHITE (-7035 -1890);
WIRE 16 -1 (-7050 -1975)(-7050 -1900);
WIRE 16 -1 (-7050 -1900)(-6575 -1900);
WIRE 16 -1 (-6425 -2250)(-6575 -2250);
WIRE 16 -1 (-6575 -2250)(-6575 -1900);
WIRE 16 -1 (-6575 -2400)(-6425 -2400);
WIRE 16 -1 (-6575 -2250)(-6575 -2400);
WIRE 16 -1 (-6575 -2700)(-6425 -2700);
WIRE 16 -1 (-6575 -2550)(-6575 -2700);
WIRE 16 -1 (-6575 -2400)(-6575 -2550);
WIRE 16 -1 (-6575 -2550)(-6425 -2550);
WIRE 16 -1 (-5625 -2550)(-4450 -2550);
FORCEPROP 0 LAST CDS_PHYS_NET_NAME JTAG_DBP_CPU_GTL_TCK_R1
J 0
(-5560 -2508);
PAINT MONO (-5560 -2508);
DISPLAY INVISIBLE (-5560 -2508);
FORCEPROP 2 LAST SIG_NAME JTAG_DBP_CPU_GTL_TCK_R1
J 0
(-5360 -2540);
DISPLAY 0.680851 (-5360 -2540);
PAINT WHITE (-5360 -2540);
WIRE 16 -1 (-2825 -2550)(-4250 -2550);
FORCEPROP 0 LAST CDS_PHYS_NET_NAME JTAG_DBP_CPU_GTL_TCK
J 0
(-3660 -2508);
PAINT MONO (-3660 -2508);
DISPLAY INVISIBLE (-3660 -2508);
FORCEPROP 2 LAST SIG_NAME JTAG_DBP_CPU_GTL_TCK
J 0
(-3660 -2540);
DISPLAY 0.680851 (-3660 -2540);
PAINT WHITE (-3660 -2540);
WIRE 16 -1 (-5625 -2400)(-4450 -2400);
FORCEPROP 0 LAST CDS_PHYS_NET_NAME JTAG_DBP_TCK_PCH_R
J 0
(-5560 -2358);
PAINT MONO (-5560 -2358);
DISPLAY INVISIBLE (-5560 -2358);
FORCEPROP 0 LAST SIG_NAME JTAG_DBP_TCK_PCH_R
J 0
(-5360 -2390);
DISPLAY 0.680851 (-5360 -2390);
PAINT WHITE (-5360 -2390);
WIRE 16 -1 (-2825 -2400)(-4250 -2400);
FORCEPROP 2 LAST SIG_NAME JTAG_DBP_TCK_PCH
J 0
(-3660 -2390);
DISPLAY 0.680851 (-3660 -2390);
PAINT WHITE (-3660 -2390);
WIRE 16 -1 (-8175 -2525)(-8300 -2525);
WIRE 16 -1 (-5625 -2200)(-5475 -2200);
FORCEPROP 0 LAST VOLTAGE 3.3
J 0
(-5550 -2200);
PAINT MONO (-5550 -2200);
DISPLAY INVISIBLE (-5550 -2200);
FORCEPROP 0 LAST CDS_PHYS_NET_NAME P3V3_AUX
J 0
(-5550 -2153);
PAINT MONO (-5550 -2153);
DISPLAY INVISIBLE (-5550 -2153);
FORCEPROP 0 LAST PHYS_NET_NAME P3V3_AUX
J 0
(-5550 -2106);
PAINT MONO (-5550 -2106);
DISPLAY INVISIBLE (-5550 -2106);
WIRE 16 -1 (-5475 -1775)(-5475 -2200);
FORCEPROP 0 LAST VOLTAGE 3.3
J 0
(-5475 -1975);
PAINT MONO (-5475 -1975);
DISPLAY INVISIBLE (-5475 -1975);
FORCEPROP 0 LAST CDS_PHYS_NET_NAME P3V3_AUX
J 0
(-5475 -1928);
PAINT MONO (-5475 -1928);
DISPLAY INVISIBLE (-5475 -1928);
FORCEPROP 0 LAST PHYS_NET_NAME P3V3_AUX
J 0
(-5475 -1881);
PAINT MONO (-5475 -1881);
DISPLAY INVISIBLE (-5475 -1881);
WIRE 16 -1 (-5475 -1775)(-5275 -1775);
WIRE 16 -1 (-5275 -1775)(-5275 -1850);
WIRE 16 -1 (-9525 -1975)(-9525 -1900);
WIRE 16 -1 (-9175 -1900)(-9525 -1900);
WIRE 16 -1 (-9175 -1975)(-9175 -1900);
WIRE 16 -1 (-9025 -1900)(-9175 -1900);
WIRE 16 -1 (-9025 -2525)(-8900 -2525);
WIRE 16 -1 (-9025 -2525)(-9025 -1900);
WIRE 16 -1 (-8900 -2575)(-9800 -2575);
FORCEPROP 0 LAST CDS_PHYS_NET_NAME JTAG_BMC_DBP_TCK
J 0
(-9610 -2527);
PAINT MONO (-9610 -2527);
DISPLAY INVISIBLE (-9610 -2527);
FORCEPROP 2 LAST SIG_NAME JTAG_BMC_DBP_TCK
J 0
(-9635 -2565);
DISPLAY 0.510638 (-9635 -2565);
PAINT WHITE (-9635 -2565);
WIRE 16 -1 (-9175 -2175)(-9175 -2300);
WIRE 16 -1 (-5625 -2700)(-4775 -2700);
FORCEPROP 0 LAST CDS_PHYS_NET_NAME TP_JTAG_BMC_1B
J 0
(-5360 -2658);
PAINT MONO (-5360 -2658);
DISPLAY INVISIBLE (-5360 -2658);
FORCEPROP 2 LAST SIG_NAME TP_JTAG_BMC_1B
J 0
(-5360 -2690);
DISPLAY 0.680851 (-5360 -2690);
PAINT WHITE (-5360 -2690);
WIRE 16 -1 (-5625 -2250)(-4775 -2250);
FORCEPROP 0 LAST CDS_PHYS_NET_NAME TP_JTAG_BMC_4B
J 0
(-5360 -2208);
PAINT MONO (-5360 -2208);
DISPLAY INVISIBLE (-5360 -2208);
FORCEPROP 2 LAST SIG_NAME TP_JTAG_BMC_4B
J 0
(-5360 -2240);
DISPLAY 0.680851 (-5360 -2240);
PAINT WHITE (-5360 -2240);
DOT 1 (-7225 -1900);
DOT 1 (-7050 -1900);
DOT 1 (-6575 -2400);
DOT 1 (-6575 -2250);
DOT 1 (-6625 -2750);
DOT 1 (-7625 -3125);
DOT 1 (-7050 -2250);
DOT 1 (-5475 -1775);
DOT 1 (-6575 -2550);
DOT 1 (-7850 -2475);
DOT 1 (-9525 -1900);
DOT 1 (-9525 -2300);
DOT 1 (-7400 -3125);
DOT 1 (-9175 -1900);
DOT 1 (-9725 -2475);
DOT 1 (-8175 -1500);
DOT 1 (-8175 -1475);
DOT 1 (-7625 -2575);
QUIT
